# BASEBOARD_FAB2 (Tioga Pass) — schematic netlist excerpt (pin names and nets, part order shuffled) for the footprints in the layout excerpt that follows; sources: Cadence DE-HDL packaged netlist, KiCad conversion of Wiwynn_Tioga_Pass_MB.brd

R4D72  RES  68.1K 1% EMPTY  pkg 0402  page 203 : A = VR_PVCCIN_CPU0_PH3_OCSET ; B = GND
CT44  CAP  1000PF 50V 10% X7R  pkg 0402LF  page 219 : A = VR_PVDDQ_DEF_PH1_SW ; B = VR_PVDDQ_DEF_PH1_SW_RC
C6G3  CAP  22UF 4V 20% X6S  pkg 0805LF  page 216 : A = PVDDQ_ABC ; B = GND

(kicad_pcb
	(version 20260206)
	(generator "pcbnew")
	(generator_version "10.0")
	(general
		(thickness 1.6)
		(legacy_teardrops no)
	)
	(paper "A4")
	(title_block
		(title "Wiwynn_Tioga_Pass_MB.brd")
		(comment 1 "Tioga Pass / footprints 1963-1965 of 4770")
	)
	(layers
		(0 "F.Cu" signal "TOP")
		(4 "In1.Cu" signal "L2GND")
		(6 "In2.Cu" signal "L3")
		(8 "In3.Cu" signal "L4GND")
		(10 "In4.Cu" signal "L5")
		(12 "In5.Cu" signal "L6GND")
		(14 "In6.Cu" signal "L7VCC")
		(16 "In7.Cu" signal "L8VCC")
		(18 "In8.Cu" signal "L9GND")
		(20 "In9.Cu" signal "L10")
		(22 "In10.Cu" signal "L11GND")
		(24 "In11.Cu" signal "L12")
		(26 "In12.Cu" signal "L13GND")
		(2 "B.Cu" signal "BOTTOM")
		(9 "F.Adhes" user "F.Adhesive")
		(11 "B.Adhes" user "B.Adhesive")
		(13 "F.Paste" user "Package Geometry/Pastemask Top")
		(15 "B.Paste" user "Package Geometry/Pastemask Bottom")
		(5 "F.SilkS" user "Ref Des/Silkscreen Top")
		(7 "B.SilkS" user "Ref Des/Silkscreen Bottom")
		(1 "F.Mask" user "Board Geometry/Soldermask Top")
		(3 "B.Mask" user "Board Geometry/Soldermask Bottom")
		(17 "Dwgs.User" user "User.Drawings")
		(19 "Cmts.User" user "User.Comments")
		(21 "Eco1.User" user "User.Eco1")
		(23 "Eco2.User" user "User.Eco2")
		(25 "Edge.Cuts" user "Board Geometry/Outline")
		(27 "Margin" user)
		(31 "F.CrtYd" user "Package Geometry/Place Bound Top")
		(29 "B.CrtYd" user "Package Geometry/Place Bound Bottom")
		(35 "F.Fab" user "Ref Des/Assembly Top")
		(33 "B.Fab" user "Ref Des/Assembly Bottom")
	)
	(footprint ""
		(layer "F.Cu")
		(at 330.835 -12.8016 180)
		(property "Reference" "C6G3"
			(at 0 0 180)
			(layer "F.SilkS")
			(hide yes)
			(effects
				(font
					(size 1.27 1.27)
				)
			)
		)
		(property "Value" ""
			(at 0 0 180)
			(layer "F.Fab")
			(effects
				(font
					(size 1.27 1.27)
				)
			)
		)
		(duplicate_pad_numbers_are_jumpers no)
		(fp_rect
			(start 0.7239 -0.2159)
			(end -0.7239 1.9939)
			(stroke
				(width 0)
				(type default)
			)
			(fill no)
			(layer "F.CrtYd")
		)
		(fp_line
			(start 0.7239 1.9939)
			(end 0.7239 -0.2159)
			(stroke
				(width 0.1)
				(type default)
			)
			(layer "F.Fab")
		)
		(fp_line
			(start 0.7239 -0.2159)
			(end -0.7239 -0.2159)
			(stroke
				(width 0.1)
				(type default)
			)
			(layer "F.Fab")
		)
		(fp_line
			(start -0.7239 1.9939)
			(end 0.7239 1.9939)
			(stroke
				(width 0.1)
				(type default)
			)
			(layer "F.Fab")
		)
		(fp_line
			(start -0.7239 -0.2159)
			(end -0.7239 1.9939)
			(stroke
				(width 0.1)
				(type default)
			)
			(layer "F.Fab")
		)
		(pad "1" smd rect
			(at 0 0 180)
			(size 1.27 1.016)
			(layers "F.Cu" "F.Mask" "F.Paste")
			(net "PVDDQ_ABC")
		)
		(pad "2" smd rect
			(at 0 1.778 180)
			(size 1.27 1.016)
			(layers "F.Cu" "F.Mask" "F.Paste")
			(net "GND")
		)
		(zone
			(layer "F.Cu")
			(hatch none 0.5)
			(connect_pads
				(clearance 0)
			)
			(min_thickness 0.25)
			(keepout
				(tracks not_allowed)
				(vias allowed)
				(pads allowed)
				(copperpour not_allowed)
				(footprints allowed)
			)
			(placement
				(enabled no)
				(sheetname "")
			)
			(fill
				(thermal_gap 0.5)
				(thermal_bridge_width 0.5)
				(island_removal_mode 0)
			)
			(polygon
				(pts
					(xy 330.2 -13.3096) (xy 331.47 -13.3096) (xy 331.47 -14.0716) (xy 330.2 -14.0716)
				)
			)
		)
	)
	(footprint ""
		(layer "F.Cu")
		(at 343.492328 -156.591 180)
		(property "Reference" "CT44"
			(at -0.8382 -0.67818 180)
			(unlocked yes)
			(layer "F.SilkS")
			(effects
				(font
					(size 0.4064 0.254)
					(thickness 0.1524)
				)
				(justify left)
			)
		)
		(property "Value" ""
			(at 0 0 180)
			(layer "F.Fab")
			(effects
				(font
					(size 1.27 1.27)
				)
			)
		)
		(duplicate_pad_numbers_are_jumpers no)
		(fp_poly
			(pts
				(xy 0.3048 -0.1016) (xy 0.3048 0.9906) (xy -0.3048 0.9906) (xy -0.3048 -0.1016)
			)
			(stroke
				(width 0)
				(type default)
			)
			(fill no)
			(layer "F.CrtYd")
		)
		(fp_line
			(start 0.3048 0.9906)
			(end 0.3048 -0.1016)
			(stroke
				(width 0.1)
				(type default)
			)
			(layer "F.Fab")
		)
		(fp_line
			(start 0.3048 -0.1016)
			(end -0.3048 -0.1016)
			(stroke
				(width 0.1)
				(type default)
			)
			(layer "F.Fab")
		)
		(fp_line
			(start -0.3048 0.9906)
			(end 0.3048 0.9906)
			(stroke
				(width 0.1)
				(type default)
			)
			(layer "F.Fab")
		)
		(fp_line
			(start -0.3048 -0.1016)
			(end -0.3048 0.9906)
			(stroke
				(width 0.1)
				(type default)
			)
			(layer "F.Fab")
		)
		(pad "1" smd rect
			(at 0 0 180)
			(size 0.508 0.508)
			(layers "F.Cu" "F.Mask" "F.Paste")
			(net "VR_PVDDQ_DEF_PH1_SW")
		)
		(pad "2" smd rect
			(at 0 0.889 180)
			(size 0.508 0.508)
			(layers "F.Cu" "F.Mask" "F.Paste")
			(net "VR_PVDDQ_DEF_PH1_SW_RC")
		)
		(zone
			(layer "F.Cu")
			(hatch none 0.5)
			(connect_pads
				(clearance 0)
			)
			(min_thickness 0.25)
			(keepout
				(tracks not_allowed)
				(vias allowed)
				(pads allowed)
				(copperpour not_allowed)
				(footprints allowed)
			)
			(placement
				(enabled no)
				(sheetname "")
			)
			(fill
				(thermal_gap 0.5)
				(thermal_bridge_width 0.5)
				(island_removal_mode 0)
			)
			(polygon
				(pts
					(xy 343.746328 -157.226) (xy 343.238328 -157.226) (xy 343.238328 -156.845) (xy 343.746328 -156.845)
				)
			)
		)
		(zone
			(layer "F.Cu")
			(hatch none 0.5)
			(connect_pads
				(clearance 0)
			)
			(min_thickness 0.25)
			(keepout
				(tracks allowed)
				(vias not_allowed)
				(pads allowed)
				(copperpour not_allowed)
				(footprints allowed)
			)
			(placement
				(enabled no)
				(sheetname "")
			)
			(fill
				(thermal_gap 0.5)
				(thermal_bridge_width 0.5)
				(island_removal_mode 0)
			)
			(polygon
				(pts
					(xy 343.746328 -156.845) (xy 343.238328 -156.845) (xy 343.238328 -157.226) (xy 343.746328 -157.226)
				)
			)
		)
	)
	(footprint ""
		(layer "F.Cu")
		(at 193.5099 -70.88124)
		(property "Reference" "R4D72"
			(at 0 0 0)
			(layer "F.SilkS")
			(hide yes)
			(effects
				(font
					(size 1.27 1.27)
				)
			)
		)
		(property "Value" ""
			(at 0 0 0)
			(layer "F.Fab")
			(effects
				(font
					(size 1.27 1.27)
				)
			)
		)
		(duplicate_pad_numbers_are_jumpers no)
		(fp_poly
			(pts
				(xy -0.2794 -0.1016) (xy 0.2794 -0.1016) (xy 0.2794 0.9906) (xy -0.2794 0.9906)
			)
			(stroke
				(width 0)
				(type default)
			)
			(fill no)
			(layer "F.CrtYd")
		)
		(fp_line
			(start -0.2794 -0.1016)
			(end -0.2794 0.9906)
			(stroke
				(width 0.1)
				(type default)
			)
			(layer "F.Fab")
		)
		(fp_line
			(start -0.2794 0.9906)
			(end 0.2794 0.9906)
			(stroke
				(width 0.1)
				(type default)
			)
			(layer "F.Fab")
		)
		(fp_line
			(start 0.2794 -0.1016)
			(end -0.2794 -0.1016)
			(stroke
				(width 0.1)
				(type default)
			)
			(layer "F.Fab")
		)
		(fp_line
			(start 0.2794 0.9906)
			(end 0.2794 -0.1016)
			(stroke
				(width 0.1)
				(type default)
			)
			(layer "F.Fab")
		)
		(pad "1" smd rect
			(at 0 0)
			(size 0.508 0.508)
			(layers "F.Cu" "F.Mask" "F.Paste")
			(net "VR_PVCCIN_CPU0_PH3_OCSET")
		)
		(pad "2" smd rect
			(at 0 0.889)
			(size 0.508 0.508)
			(layers "F.Cu" "F.Mask" "F.Paste")
			(net "GND")
		)
		(zone
			(layer "F.Cu")
			(hatch none 0.5)
			(connect_pads
				(clearance 0)
			)
			(min_thickness 0.25)
			(keepout
				(tracks allowed)
				(vias not_allowed)
				(pads allowed)
				(copperpour not_allowed)
				(footprints allowed)
			)
			(placement
				(enabled no)
				(sheetname "")
			)
			(fill
				(thermal_gap 0.5)
				(thermal_bridge_width 0.5)
				(island_removal_mode 0)
			)
			(polygon
				(pts
					(xy 193.2559 -70.62724) (xy 193.7639 -70.62724) (xy 193.7639 -70.24624) (xy 193.2559 -70.24624)
				)
			)
		)
		(zone
			(layer "F.Cu")
			(hatch none 0.5)
			(connect_pads
				(clearance 0)
			)
			(min_thickness 0.25)
			(keepout
				(tracks not_allowed)
				(vias allowed)
				(pads allowed)
				(copperpour not_allowed)
				(footprints allowed)
			)
			(placement
				(enabled no)
				(sheetname "")
			)
			(fill
				(thermal_gap 0.5)
				(thermal_bridge_width 0.5)
				(island_removal_mode 0)
			)
			(polygon
				(pts
					(xy 193.2559 -70.24624) (xy 193.7639 -70.24624) (xy 193.7639 -70.62724) (xy 193.2559 -70.62724)
				)
			)
		)
	)
)
